(kicad_pcb
	(version 20241229)
	(generator "pcbnew")
	(generator_version "9.0")
	(general
		(thickness 1.294)
		(legacy_teardrops no)
	)
	(paper "A3")
	(title_block
		(title "Kintex 410T devboard")
		(date "2024-04-03")
		(rev "1.1.2")
		(comment 9 "footprints 963-968 of 975")
	)
	(layers
		(0 "F.Cu" mixed)
		(4 "In1.Cu" power)
		(6 "In2.Cu" power)
		(8 "In3.Cu" mixed)
		(10 "In4.Cu" power)
		(12 "In5.Cu" mixed)
		(14 "In6.Cu" power)
		(16 "In7.Cu" mixed)
		(18 "In8.Cu" power)
		(2 "B.Cu" mixed)
		(9 "F.Adhes" user "F.Adhesive")
		(11 "B.Adhes" user "B.Adhesive")
		(13 "F.Paste" user)
		(15 "B.Paste" user)
		(5 "F.SilkS" user "F.Silkscreen")
		(7 "B.SilkS" user "B.Silkscreen")
		(1 "F.Mask" user)
		(3 "B.Mask" user)
		(17 "Dwgs.User" user "User.Drawings")
		(19 "Cmts.User" user "User.Comments")
		(21 "Eco1.User" user "User.Eco1")
		(23 "Eco2.User" user "User.Eco2")
		(25 "Edge.Cuts" user)
		(27 "Margin" user)
		(31 "F.CrtYd" user "F.Courtyard")
		(29 "B.CrtYd" user "B.Courtyard")
		(35 "F.Fab" user)
		(33 "B.Fab" user)
	)
	(footprint "antmicro-footprints:R_Array_4x0201_Panasonic_EXB18V"
		(layer "B.Cu")
		(at 165.999999 144.999999)
		(property "Reference" "R14"
			(at -4.299999 6.250001 0)
			(layer "B.SilkS")
			(effects
				(font
					(size 0.7 0.7)
					(thickness 0.15)
				)
				(justify left bottom mirror)
			)
		)
		(property "Value" "4x39R_0201_array"
			(at -1.1 -1.8 0)
			(layer "B.Fab")
			(effects
				(font
					(size 0.7 0.7)
					(thickness 0.15)
				)
				(justify right bottom mirror)
			)
		)
		(property "Description" "Fixed Network Resistor, 39 ohm, Isolated, 4 Resistors, 0502 [1406 Metric], Flat, ± 5%"
			(at 0 0 0)
			(layer "F.Fab")
			(hide yes)
			(effects
				(font
					(size 1.27 1.27)
					(thickness 0.15)
				)
			)
		)
		(property "Author" "Antmicro"
			(at 0 0 0)
			(layer "B.Fab")
			(hide yes)
			(effects
				(font
					(size 1 1)
					(thickness 0.15)
				)
				(justify mirror)
			)
		)
		(property "License" "Apache-2.0"
			(at 0 0 0)
			(layer "B.Fab")
			(hide yes)
			(effects
				(font
					(size 1 1)
					(thickness 0.15)
				)
				(justify mirror)
			)
		)
		(property "MPN" "EXB-18V390JX"
			(at 0 0 0)
			(layer "B.Fab")
			(hide yes)
			(effects
				(font
					(size 1 1)
					(thickness 0.15)
				)
				(justify mirror)
			)
		)
		(property "Manufacturer" "Panasonic"
			(at 0 0 0)
			(layer "B.Fab")
			(hide yes)
			(effects
				(font
					(size 1 1)
					(thickness 0.15)
				)
				(justify mirror)
			)
		)
		(property "Val" "4x39R_0201"
			(at 0 0 0)
			(layer "B.Fab")
			(hide yes)
			(effects
				(font
					(size 1 1)
					(thickness 0.15)
				)
				(justify mirror)
			)
		)
		(sheetname "DRAM + SRAM")
		(sheetfile "ram.kicad_sch")
		(attr smd)
		(fp_line
			(start -0.8 0.45)
			(end -0.8 -0.45)
			(stroke
				(width 0.12)
				(type solid)
			)
			(layer "B.SilkS")
		)
		(fp_line
			(start 0.8 0.45)
			(end 0.8 -0.45)
			(stroke
				(width 0.12)
				(type solid)
			)
			(layer "B.SilkS")
		)
		(fp_rect
			(start -0.898 0.66)
			(end 0.898 -0.65)
			(stroke
				(width 0.05)
				(type solid)
			)
			(fill no)
			(layer "B.CrtYd")
		)
		(pad "1" smd roundrect
			(at -0.6 -0.298)
			(size 0.2 0.4)
			(layers "B.Cu" "B.Mask" "B.Paste")
			(roundrect_rratio 0.25)
			(net 533 "/DRAM + SRAM/DDR.A2")
			(pinfunction "R1.1")
			(pintype "passive")
		)
		(pad "2" smd roundrect
			(at -0.202 -0.298)
			(size 0.2 0.4)
			(layers "B.Cu" "B.Mask" "B.Paste")
			(roundrect_rratio 0.25)
			(net 534 "/DRAM + SRAM/DDR.A3")
			(pinfunction "R2.1")
			(pintype "passive")
		)
		(pad "3" smd roundrect
			(at 0.2 -0.298)
			(size 0.2 0.4)
			(layers "B.Cu" "B.Mask" "B.Paste")
			(roundrect_rratio 0.25)
			(net 531 "/DRAM + SRAM/DDR.A0")
			(pinfunction "R3.1")
			(pintype "passive")
		)
		(pad "4" smd roundrect
			(at 0.598 -0.298)
			(size 0.2 0.4)
			(layers "B.Cu" "B.Mask" "B.Paste")
			(roundrect_rratio 0.25)
			(net 547 "/DRAM + SRAM/DDR.BA0")
			(pinfunction "R4.1")
			(pintype "passive")
		)
		(pad "5" smd roundrect
			(at 0.598 0.3)
			(size 0.2 0.4)
			(layers "B.Cu" "B.Mask" "B.Paste")
			(roundrect_rratio 0.25)
			(net 7 "+0V675_VTT")
			(pinfunction "R4.2")
			(pintype "passive")
		)
		(pad "6" smd roundrect
			(at 0.2 0.3)
			(size 0.2 0.4)
			(layers "B.Cu" "B.Mask" "B.Paste")
			(roundrect_rratio 0.25)
			(net 7 "+0V675_VTT")
			(pinfunction "R3.2")
			(pintype "passive")
		)
		(pad "7" smd roundrect
			(at -0.202 0.3)
			(size 0.2 0.4)
			(layers "B.Cu" "B.Mask" "B.Paste")
			(roundrect_rratio 0.25)
			(net 7 "+0V675_VTT")
			(pinfunction "R2.2")
			(pintype "passive")
		)
		(pad "8" smd roundrect
			(at -0.6 0.3)
			(size 0.2 0.4)
			(layers "B.Cu" "B.Mask" "B.Paste")
			(roundrect_rratio 0.25)
			(net 7 "+0V675_VTT")
			(pinfunction "R1.2")
			(pintype "passive")
		)
	)
	(footprint "antmicro-footprints:C_0402_1005Metric"
		(layer "B.Cu")
		(at 173.599999 147.999999 -90)
		(descr "Capacitor SMD 0402")
		(tags "capacitor SMD 0402")
		(property "Reference" "C187"
			(at 0.775001 -0.375001 90)
			(layer "B.SilkS")
			(effects
				(font
					(size 0.7 0.7)
					(thickness 0.15)
				)
				(justify left bottom mirror)
			)
		)
		(property "Value" "C_100n_0402"
			(at 0 -1.169 90)
			(layer "B.Fab")
			(effects
				(font
					(size 0.7 0.7)
					(thickness 0.15)
				)
				(justify left bottom mirror)
			)
		)
		(property "Description" "SMD Multilayer Ceramic Capacitor, 0.1 µF, 50 V, 0402 [1005 Metric], ± 10%, X5R, GRM Series"
			(at 0 0 270)
			(layer "F.Fab")
			(hide yes)
			(effects
				(font
					(size 1.27 1.27)
					(thickness 0.15)
				)
			)
		)
		(property "Author" "Antmicro"
			(at 25.6 321.599998 0)
			(layer "B.Fab")
			(hide yes)
			(effects
				(font
					(size 1 1)
					(thickness 0.15)
				)
				(justify mirror)
			)
		)
		(property "Dielectric" "X5R"
			(at 25.6 321.599998 0)
			(layer "B.Fab")
			(hide yes)
			(effects
				(font
					(size 1 1)
					(thickness 0.15)
				)
				(justify mirror)
			)
		)
		(property "License" "Apache-2.0"
			(at 25.6 321.599998 0)
			(layer "B.Fab")
			(hide yes)
			(effects
				(font
					(size 1 1)
					(thickness 0.15)
				)
				(justify mirror)
			)
		)
		(property "MPN" "GRM155R61H104KE14D"
			(at 25.6 321.599998 0)
			(layer "B.Fab")
			(hide yes)
			(effects
				(font
					(size 1 1)
					(thickness 0.15)
				)
				(justify mirror)
			)
		)
		(property "Manufacturer" "Murata"
			(at 25.6 321.599998 0)
			(layer "B.Fab")
			(hide yes)
			(effects
				(font
					(size 1 1)
					(thickness 0.15)
				)
				(justify mirror)
			)
		)
		(property "Val" "100n"
			(at 25.6 321.599998 0)
			(layer "B.Fab")
			(hide yes)
			(effects
				(font
					(size 1 1)
					(thickness 0.15)
				)
				(justify mirror)
			)
		)
		(property "Voltage" "50V"
			(at 25.6 321.599998 0)
			(layer "B.Fab")
			(hide yes)
			(effects
				(font
					(size 1 1)
					(thickness 0.15)
				)
				(justify mirror)
			)
		)
		(sheetname "DRAM + SRAM")
		(sheetfile "ram.kicad_sch")
		(attr smd)
		(fp_rect
			(start -0.925 0.47)
			(end 0.925 -0.47)
			(stroke
				(width 0.05)
				(type default)
			)
			(fill no)
			(layer "B.CrtYd")
		)
		(fp_line
			(start -0.494 0.25)
			(end 0.504 0.25)
			(stroke
				(width 0.15)
				(type solid)
			)
			(layer "B.Fab")
		)
		(fp_line
			(start 0.504 0.25)
			(end 0.504 -0.248)
			(stroke
				(width 0.15)
				(type solid)
			)
			(layer "B.Fab")
		)
		(fp_line
			(start -0.494 -0.248)
			(end -0.494 0.25)
			(stroke
				(width 0.15)
				(type solid)
			)
			(layer "B.Fab")
		)
		(fp_line
			(start 0.504 -0.248)
			(end -0.494 -0.248)
			(stroke
				(width 0.15)
				(type solid)
			)
			(layer "B.Fab")
		)
		(pad "1" smd roundrect
			(at -0.48 0 270)
			(size 0.59 0.64)
			(layers "B.Cu" "B.Mask" "B.Paste")
			(roundrect_rratio 0.25)
			(net 1 "GND")
			(pintype "passive")
		)
		(pad "2" smd roundrect
			(at 0.48 0 270)
			(size 0.59 0.64)
			(layers "B.Cu" "B.Mask" "B.Paste")
			(roundrect_rratio 0.25)
			(net 25 "+1V35")
			(pintype "passive")
		)
	)
	(footprint "antmicro-footprints:C_0603_1608Metric"
		(layer "B.Cu")
		(at 200 136.6 90)
		(descr "Capacitor SMD 0603")
		(tags "capacitor 0603")
		(property "Reference" "C386"
			(at 27.425 25.725 90)
			(layer "B.SilkS")
			(effects
				(font
					(size 0.7 0.7)
					(thickness 0.15)
				)
				(justify right bottom mirror)
			)
		)
		(property "Value" "C_47u_0603"
			(at 0 -1.6 90)
			(layer "B.Fab")
			(effects
				(font
					(size 0.7 0.7)
					(thickness 0.15)
				)
				(justify right bottom mirror)
			)
		)
		(property "Description" "SMD Multilayer Ceramic Capacitor, 47 µF, 6.3 V, 0603 [1608 Metric], ± 20%, X5R, GRM Series"
			(at 0 0 90)
			(layer "F.Fab")
			(hide yes)
			(effects
				(font
					(size 1.27 1.27)
					(thickness 0.15)
				)
			)
		)
		(property "Author" "Antmicro"
			(at 336.6 -63.4 0)
			(layer "B.Fab")
			(hide yes)
			(effects
				(font
					(size 1 1)
					(thickness 0.15)
				)
				(justify mirror)
			)
		)
		(property "Dielectric" ""
			(at 336.6 -63.4 0)
			(layer "B.Fab")
			(hide yes)
			(effects
				(font
					(size 1 1)
					(thickness 0.15)
				)
				(justify mirror)
			)
		)
		(property "License" "Apache-2.0"
			(at 336.6 -63.4 0)
			(layer "B.Fab")
			(hide yes)
			(effects
				(font
					(size 1 1)
					(thickness 0.15)
				)
				(justify mirror)
			)
		)
		(property "MPN" "GRM188R60J476ME15D"
			(at 336.6 -63.4 0)
			(layer "B.Fab")
			(hide yes)
			(effects
				(font
					(size 1 1)
					(thickness 0.15)
				)
				(justify mirror)
			)
		)
		(property "Manufacturer" "Murata"
			(at 336.6 -63.4 0)
			(layer "B.Fab")
			(hide yes)
			(effects
				(font
					(size 1 1)
					(thickness 0.15)
				)
				(justify mirror)
			)
		)
		(property "Val" "47u"
			(at 336.6 -63.4 0)
			(layer "B.Fab")
			(hide yes)
			(effects
				(font
					(size 1 1)
					(thickness 0.15)
				)
				(justify mirror)
			)
		)
		(property "Voltage" ""
			(at 336.6 -63.4 0)
			(layer "B.Fab")
			(hide yes)
			(effects
				(font
					(size 1 1)
					(thickness 0.15)
				)
				(justify mirror)
			)
		)
		(sheetname "FPGA supply")
		(sheetfile "fpga-supply.kicad_sch")
		(attr smd)
		(fp_line
			(start -0.15 -0.4)
			(end 0.15 -0.4)
			(stroke
				(width 0.15)
				(type solid)
			)
			(layer "B.SilkS")
		)
		(fp_line
			(start -0.15 0.4)
			(end 0.15 0.4)
			(stroke
				(width 0.15)
				(type solid)
			)
			(layer "B.SilkS")
		)
		(fp_rect
			(start -1.25 0.65)
			(end 1.25 -0.65)
			(stroke
				(width 0.05)
				(type solid)
			)
			(fill no)
			(layer "B.CrtYd")
		)
		(fp_rect
			(start -0.8 0.4)
			(end 0.8 -0.4)
			(stroke
				(width 0.15)
				(type solid)
			)
			(fill no)
			(layer "B.Fab")
		)
		(pad "1" smd roundrect
			(at -0.7 0 90)
			(size 0.8 1)
			(layers "B.Cu" "B.Mask" "B.Paste")
			(roundrect_rratio 0.2)
			(net 1 "GND")
			(pintype "passive")
		)
		(pad "2" smd roundrect
			(at 0.7 0 90)
			(size 0.8 1)
			(layers "B.Cu" "B.Mask" "B.Paste")
			(roundrect_rratio 0.2)
			(net 650 "+1V0")
			(pintype "passive")
		)
	)
	(footprint "antmicro-footprints:C_0603_1608Metric"
		(layer "B.Cu")
		(at 184.100001 133.000001)
		(descr "Capacitor SMD 0603")
		(tags "capacitor 0603")
		(property "Reference" "C120"
			(at -3.850001 0.369999 0)
			(layer "B.SilkS")
			(effects
				(font
					(size 0.7 0.7)
					(thickness 0.15)
				)
				(justify right bottom mirror)
			)
		)
		(property "Value" "C_47u_0603"
			(at 0 -1.6 0)
			(layer "B.Fab")
			(effects
				(font
					(size 0.7 0.7)
					(thickness 0.15)
				)
				(justify right bottom mirror)
			)
		)
		(property "Description" "SMD Multilayer Ceramic Capacitor, 47 µF, 6.3 V, 0603 [1608 Metric], ± 20%, X5R, GRM Series"
			(at 0 0 0)
			(layer "F.Fab")
			(hide yes)
			(effects
				(font
					(size 1.27 1.27)
					(thickness 0.15)
				)
			)
		)
		(property "Author" "Antmicro"
			(at 0 0 0)
			(layer "B.Fab")
			(hide yes)
			(effects
				(font
					(size 1 1)
					(thickness 0.15)
				)
				(justify mirror)
			)
		)
		(property "Dielectric" ""
			(at 0 0 0)
			(layer "B.Fab")
			(hide yes)
			(effects
				(font
					(size 1 1)
					(thickness 0.15)
				)
				(justify mirror)
			)
		)
		(property "License" "Apache-2.0"
			(at 0 0 0)
			(layer "B.Fab")
			(hide yes)
			(effects
				(font
					(size 1 1)
					(thickness 0.15)
				)
				(justify mirror)
			)
		)
		(property "MPN" "GRM188R60J476ME15D"
			(at 0 0 0)
			(layer "B.Fab")
			(hide yes)
			(effects
				(font
					(size 1 1)
					(thickness 0.15)
				)
				(justify mirror)
			)
		)
		(property "Manufacturer" "Murata"
			(at 0 0 0)
			(layer "B.Fab")
			(hide yes)
			(effects
				(font
					(size 1 1)
					(thickness 0.15)
				)
				(justify mirror)
			)
		)
		(property "Val" "47u"
			(at 0 0 0)
			(layer "B.Fab")
			(hide yes)
			(effects
				(font
					(size 1 1)
					(thickness 0.15)
				)
				(justify mirror)
			)
		)
		(property "Voltage" ""
			(at 0 0 0)
			(layer "B.Fab")
			(hide yes)
			(effects
				(font
					(size 1 1)
					(thickness 0.15)
				)
				(justify mirror)
			)
		)
		(sheetname "FPGA supply")
		(sheetfile "fpga-supply.kicad_sch")
		(attr smd)
		(fp_line
			(start -0.15 -0.4)
			(end 0.15 -0.4)
			(stroke
				(width 0.15)
				(type solid)
			)
			(layer "B.SilkS")
		)
		(fp_line
			(start -0.15 0.4)
			(end 0.15 0.4)
			(stroke
				(width 0.15)
				(type solid)
			)
			(layer "B.SilkS")
		)
		(fp_rect
			(start -1.25 0.65)
			(end 1.25 -0.65)
			(stroke
				(width 0.05)
				(type solid)
			)
			(fill no)
			(layer "B.CrtYd")
		)
		(fp_rect
			(start -0.8 0.4)
			(end 0.8 -0.4)
			(stroke
				(width 0.15)
				(type solid)
			)
			(fill no)
			(layer "B.Fab")
		)
		(pad "1" smd roundrect
			(at -0.7 0)
			(size 0.8 1)
			(layers "B.Cu" "B.Mask" "B.Paste")
			(roundrect_rratio 0.2)
			(net 1 "GND")
			(pintype "passive")
		)
		(pad "2" smd roundrect
			(at 0.7 0)
			(size 0.8 1)
			(layers "B.Cu" "B.Mask" "B.Paste")
			(roundrect_rratio 0.2)
			(net 8 "+1V2_MGTAVTT")
			(pintype "passive")
		)
	)
	(footprint "antmicro-footprints:C_0402_1005Metric"
		(layer "B.Cu")
		(at 169.6 147.999999 90)
		(descr "Capacitor SMD 0402")
		(tags "capacitor SMD 0402")
		(property "Reference" "C181"
			(at 0.124999 -1 0)
			(layer "B.SilkS")
			(effects
				(font
					(size 0.7 0.7)
					(thickness 0.15)
				)
				(justify left bottom mirror)
			)
		)
		(property "Value" "C_100n_0402"
			(at 0 -1.169 270)
			(layer "B.Fab")
			(effects
				(font
					(size 0.7 0.7)
					(thickness 0.15)
				)
				(justify left bottom mirror)
			)
		)
		(property "Description" "SMD Multilayer Ceramic Capacitor, 0.1 µF, 50 V, 0402 [1005 Metric], ± 10%, X5R, GRM Series"
			(at 0 0 90)
			(layer "F.Fab")
			(hide yes)
			(effects
				(font
					(size 1.27 1.27)
					(thickness 0.15)
				)
			)
		)
		(property "Author" "Antmicro"
			(at 317.599999 -21.600001 0)
			(layer "B.Fab")
			(hide yes)
			(effects
				(font
					(size 1 1)
					(thickness 0.15)
				)
				(justify mirror)
			)
		)
		(property "Dielectric" "X5R"
			(at 317.599999 -21.600001 0)
			(layer "B.Fab")
			(hide yes)
			(effects
				(font
					(size 1 1)
					(thickness 0.15)
				)
				(justify mirror)
			)
		)
		(property "License" "Apache-2.0"
			(at 317.599999 -21.600001 0)
			(layer "B.Fab")
			(hide yes)
			(effects
				(font
					(size 1 1)
					(thickness 0.15)
				)
				(justify mirror)
			)
		)
		(property "MPN" "GRM155R61H104KE14D"
			(at 317.599999 -21.600001 0)
			(layer "B.Fab")
			(hide yes)
			(effects
				(font
					(size 1 1)
					(thickness 0.15)
				)
				(justify mirror)
			)
		)
		(property "Manufacturer" "Murata"
			(at 317.599999 -21.600001 0)
			(layer "B.Fab")
			(hide yes)
			(effects
				(font
					(size 1 1)
					(thickness 0.15)
				)
				(justify mirror)
			)
		)
		(property "Val" "100n"
			(at 317.599999 -21.600001 0)
			(layer "B.Fab")
			(hide yes)
			(effects
				(font
					(size 1 1)
					(thickness 0.15)
				)
				(justify mirror)
			)
		)
		(property "Voltage" "50V"
			(at 317.599999 -21.600001 0)
			(layer "B.Fab")
			(hide yes)
			(effects
				(font
					(size 1 1)
					(thickness 0.15)
				)
				(justify mirror)
			)
		)
		(sheetname "DRAM + SRAM")
		(sheetfile "ram.kicad_sch")
		(attr smd)
		(fp_rect
			(start -0.925 0.47)
			(end 0.925 -0.47)
			(stroke
				(width 0.05)
				(type default)
			)
			(fill no)
			(layer "B.CrtYd")
		)
		(fp_line
			(start 0.504 -0.248)
			(end -0.494 -0.248)
			(stroke
				(width 0.15)
				(type solid)
			)
			(layer "B.Fab")
		)
		(fp_line
			(start -0.494 -0.248)
			(end -0.494 0.25)
			(stroke
				(width 0.15)
				(type solid)
			)
			(layer "B.Fab")
		)
		(fp_line
			(start 0.504 0.25)
			(end 0.504 -0.248)
			(stroke
				(width 0.15)
				(type solid)
			)
			(layer "B.Fab")
		)
		(fp_line
			(start -0.494 0.25)
			(end 0.504 0.25)
			(stroke
				(width 0.15)
				(type solid)
			)
			(layer "B.Fab")
		)
		(pad "1" smd roundrect
			(at -0.48 0 90)
			(size 0.59 0.64)
			(layers "B.Cu" "B.Mask" "B.Paste")
			(roundrect_rratio 0.25)
			(net 1 "GND")
			(pintype "passive")
		)
		(pad "2" smd roundrect
			(at 0.48 0 90)
			(size 0.59 0.64)
			(layers "B.Cu" "B.Mask" "B.Paste")
			(roundrect_rratio 0.25)
			(net 25 "+1V35")
			(pintype "passive")
		)
	)
	(footprint "antmicro-footprints:C_0603_1608Metric"
		(layer "B.Cu")
		(at 200 123.55 -90)
		(descr "Capacitor SMD 0603")
		(tags "capacitor 0603")
		(property "Reference" "C378"
			(at -31.575 -25.775 90)
			(layer "B.SilkS")
			(effects
				(font
					(size 0.7 0.7)
					(thickness 0.15)
				)
				(justify left bottom mirror)
			)
		)
		(property "Value" "C_47u_0603"
			(at 0 -1.6 90)
			(layer "B.Fab")
			(effects
				(font
					(size 0.7 0.7)
					(thickness 0.15)
				)
				(justify left bottom mirror)
			)
		)
		(property "Description" "SMD Multilayer Ceramic Capacitor, 47 µF, 6.3 V, 0603 [1608 Metric], ± 20%, X5R, GRM Series"
			(at 0 0 270)
			(layer "F.Fab")
			(hide yes)
			(effects
				(font
					(size 1.27 1.27)
					(thickness 0.15)
				)
			)
		)
		(property "Author" "Antmicro"
			(at 76.45 323.55 0)
			(layer "B.Fab")
			(hide yes)
			(effects
				(font
					(size 1 1)
					(thickness 0.15)
				)
				(justify mirror)
			)
		)
		(property "Dielectric" ""
			(at 76.45 323.55 0)
			(layer "B.Fab")
			(hide yes)
			(effects
				(font
					(size 1 1)
					(thickness 0.15)
				)
				(justify mirror)
			)
		)
		(property "License" "Apache-2.0"
			(at 76.45 323.55 0)
			(layer "B.Fab")
			(hide yes)
			(effects
				(font
					(size 1 1)
					(thickness 0.15)
				)
				(justify mirror)
			)
		)
		(property "MPN" "GRM188R60J476ME15D"
			(at 76.45 323.55 0)
			(layer "B.Fab")
			(hide yes)
			(effects
				(font
					(size 1 1)
					(thickness 0.15)
				)
				(justify mirror)
			)
		)
		(property "Manufacturer" "Murata"
			(at 76.45 323.55 0)
			(layer "B.Fab")
			(hide yes)
			(effects
				(font
					(size 1 1)
					(thickness 0.15)
				)
				(justify mirror)
			)
		)
		(property "Val" "47u"
			(at 76.45 323.55 0)
			(layer "B.Fab")
			(hide yes)
			(effects
				(font
					(size 1 1)
					(thickness 0.15)
				)
				(justify mirror)
			)
		)
		(property "Voltage" ""
			(at 76.45 323.55 0)
			(layer "B.Fab")
			(hide yes)
			(effects
				(font
					(size 1 1)
					(thickness 0.15)
				)
				(justify mirror)
			)
		)
		(sheetname "FPGA supply")
		(sheetfile "fpga-supply.kicad_sch")
		(attr smd)
		(fp_line
			(start -0.15 0.4)
			(end 0.15 0.4)
			(stroke
				(width 0.15)
				(type solid)
			)
			(layer "B.SilkS")
		)
		(fp_line
			(start -0.15 -0.4)
			(end 0.15 -0.4)
			(stroke
				(width 0.15)
				(type solid)
			)
			(layer "B.SilkS")
		)
		(fp_rect
			(start -1.25 0.65)
			(end 1.25 -0.65)
			(stroke
				(width 0.05)
				(type solid)
			)
			(fill no)
			(layer "B.CrtYd")
		)
		(fp_rect
			(start -0.8 0.4)
			(end 0.8 -0.4)
			(stroke
				(width 0.15)
				(type solid)
			)
			(fill no)
			(layer "B.Fab")
		)
		(pad "1" smd roundrect
			(at -0.7 0 270)
			(size 0.8 1)
			(layers "B.Cu" "B.Mask" "B.Paste")
			(roundrect_rratio 0.2)
			(net 1 "GND")
			(pintype "passive")
		)
		(pad "2" smd roundrect
			(at 0.7 0 270)
			(size 0.8 1)
			(layers "B.Cu" "B.Mask" "B.Paste")
			(roundrect_rratio 0.2)
			(net 650 "+1V0")
			(pintype "passive")
		)
	)
)
